# SCM (Grand Teton) — schematic netlist excerpt (pin names and nets, part order shuffled) for the footprints in the layout excerpt that follows; sources: Cadence DE-HDL packaged netlist, KiCad conversion of 12092022_DA0F0TMDCD0_F0T_Management_Board_D_brd_V3_OCP.brd

R632  Q_RES  0 5% CHIP  pkg 0402LF  page 28 : A = SMB_DEBUG_AUX_LVC3_USB_SCL ; B = SMB_DEBUG_AUX_LVC3_USB_R3_SCL
R309  Q_RES  33.2 1% CHIP  pkg 0402LF  page 13 : A = SPI_BMC_TPM_MOSI_R1 ; B = SPI_BMC_TPM_MOSI

(kicad_pcb
	(version 20260206)
	(generator "pcbnew")
	(generator_version "10.0")
	(general
		(thickness 1.6)
		(legacy_teardrops no)
	)
	(paper "A4")
	(title_block
		(title "12092022_DA0F0TMDCD0_F0T_Management_Board_D_brd_V3_OCP.brd")
		(comment 1 "Grand Teton / footprints 921-922 of 1440")
	)
	(layers
		(0 "F.Cu" signal "TOP")
		(4 "In1.Cu" signal "GND")
		(6 "In2.Cu" signal "IN1")
		(8 "In3.Cu" signal "GND1")
		(10 "In4.Cu" signal "IN2")
		(12 "In5.Cu" signal "VCC")
		(14 "In6.Cu" signal "VCC1")
		(16 "In7.Cu" signal "IN3")
		(18 "In8.Cu" signal "GND2")
		(20 "In9.Cu" signal "IN4")
		(22 "In10.Cu" signal "GND3")
		(2 "B.Cu" signal "BOTTOM")
		(9 "F.Adhes" user "F.Adhesive")
		(11 "B.Adhes" user "B.Adhesive")
		(13 "F.Paste" user "Package Geometry/Pastemask Top")
		(15 "B.Paste" user "Package Geometry/Pastemask Bottom")
		(5 "F.SilkS" user "Ref Des/Silkscreen Top")
		(7 "B.SilkS" user "Ref Des/Silkscreen Bottom")
		(1 "F.Mask" user "Board Geometry/Soldermask Top")
		(3 "B.Mask" user "Board Geometry/Soldermask Bottom")
		(17 "Dwgs.User" user "User.Drawings")
		(19 "Cmts.User" user "User.Comments")
		(21 "Eco1.User" user "User.Eco1")
		(23 "Eco2.User" user "User.Eco2")
		(25 "Edge.Cuts" user "Board Geometry/Outline")
		(27 "Margin" user)
		(31 "F.CrtYd" user "Package Geometry/Place Bound Top")
		(29 "B.CrtYd" user "Package Geometry/Place Bound Bottom")
		(35 "F.Fab" user "Ref Des/Assembly Top")
		(33 "B.Fab" user "Ref Des/Assembly Bottom")
	)
	(footprint ""
		(layer "B.Cu")
		(at 66.4972 -72.4662 -90)
		(property "Reference" "R309"
			(at 0 0 90)
			(layer "B.SilkS")
			(hide yes)
			(effects
				(font
					(size 1.27 1.27)
				)
				(justify mirror)
			)
		)
		(property "Value" ""
			(at 0 0 90)
			(layer "B.Fab")
			(effects
				(font
					(size 1.27 1.27)
				)
				(justify mirror)
			)
		)
		(duplicate_pad_numbers_are_jumpers no)
		(fp_line
			(start -0.7874 0.4064)
			(end 0.7874 0.4064)
			(stroke
				(width 0.1524)
				(type default)
			)
			(layer "B.SilkS")
		)
		(fp_line
			(start 0.7874 0.4064)
			(end 0.7874 -0.4064)
			(stroke
				(width 0.1524)
				(type default)
			)
			(layer "B.SilkS")
		)
		(fp_line
			(start -0.7874 -0.4064)
			(end -0.7874 0.4064)
			(stroke
				(width 0.1524)
				(type default)
			)
			(layer "B.SilkS")
		)
		(fp_line
			(start 0.7874 -0.4064)
			(end -0.7874 -0.4064)
			(stroke
				(width 0.1524)
				(type default)
			)
			(layer "B.SilkS")
		)
		(fp_line
			(start -0.67945 0.3048)
			(end -0.120396 0.3048)
			(stroke
				(width 0.1)
				(type default)
			)
			(layer "B.Fab")
		)
		(fp_line
			(start -0.120396 0.3048)
			(end -0.120396 0.2794)
			(stroke
				(width 0.1)
				(type default)
			)
			(layer "B.Fab")
		)
		(fp_line
			(start 0.12065 0.3048)
			(end 0.67945 0.3048)
			(stroke
				(width 0.1)
				(type default)
			)
			(layer "B.Fab")
		)
		(fp_line
			(start 0.67945 0.3048)
			(end 0.67945 -0.305054)
			(stroke
				(width 0.1)
				(type default)
			)
			(layer "B.Fab")
		)
		(fp_line
			(start -0.120396 0.2794)
			(end 0.12065 0.2794)
			(stroke
				(width 0.1)
				(type default)
			)
			(layer "B.Fab")
		)
		(fp_line
			(start 0.12065 0.2794)
			(end 0.12065 0.3048)
			(stroke
				(width 0.1)
				(type default)
			)
			(layer "B.Fab")
		)
		(fp_line
			(start -0.12065 -0.2794)
			(end -0.12065 -0.3048)
			(stroke
				(width 0.1)
				(type default)
			)
			(layer "B.Fab")
		)
		(fp_line
			(start 0.12065 -0.2794)
			(end -0.12065 -0.2794)
			(stroke
				(width 0.1)
				(type default)
			)
			(layer "B.Fab")
		)
		(fp_line
			(start -0.67945 -0.3048)
			(end -0.67945 0.3048)
			(stroke
				(width 0.1)
				(type default)
			)
			(layer "B.Fab")
		)
		(fp_line
			(start -0.12065 -0.3048)
			(end -0.67945 -0.3048)
			(stroke
				(width 0.1)
				(type default)
			)
			(layer "B.Fab")
		)
		(fp_line
			(start 0.12065 -0.305054)
			(end 0.12065 -0.2794)
			(stroke
				(width 0.1)
				(type default)
			)
			(layer "B.Fab")
		)
		(fp_line
			(start 0.67945 -0.305054)
			(end 0.12065 -0.305054)
			(stroke
				(width 0.1)
				(type default)
			)
			(layer "B.Fab")
		)
		(pad "1" smd circle
			(at 0.40005 0 90)
			(size 0 0)
			(layers "B.Cu" "B.Mask" "B.Paste")
			(net "SPI_BMC_TPM_MOSI_R1")
		)
		(pad "2" smd circle
			(at -0.40005 0 90)
			(size 0 0)
			(layers "B.Cu" "B.Mask" "B.Paste")
			(net "SPI_BMC_TPM_MOSI")
		)
	)
	(footprint ""
		(layer "B.Cu")
		(at 51.2445 -93.2815 180)
		(property "Reference" "R632"
			(at 0 0 0)
			(layer "B.SilkS")
			(hide yes)
			(effects
				(font
					(size 1.27 1.27)
				)
				(justify mirror)
			)
		)
		(property "Value" ""
			(at 0 0 0)
			(layer "B.Fab")
			(effects
				(font
					(size 1.27 1.27)
				)
				(justify mirror)
			)
		)
		(duplicate_pad_numbers_are_jumpers no)
		(fp_line
			(start 0.7874 0.4064)
			(end 0.7874 -0.4064)
			(stroke
				(width 0.1524)
				(type default)
			)
			(layer "B.SilkS")
		)
		(fp_line
			(start 0.7874 -0.4064)
			(end -0.7874 -0.4064)
			(stroke
				(width 0.1524)
				(type default)
			)
			(layer "B.SilkS")
		)
		(fp_line
			(start -0.7874 0.4064)
			(end 0.7874 0.4064)
			(stroke
				(width 0.1524)
				(type default)
			)
			(layer "B.SilkS")
		)
		(fp_line
			(start -0.7874 -0.4064)
			(end -0.7874 0.4064)
			(stroke
				(width 0.1524)
				(type default)
			)
			(layer "B.SilkS")
		)
		(fp_line
			(start 0.67945 0.3048)
			(end 0.67945 -0.305054)
			(stroke
				(width 0.1)
				(type default)
			)
			(layer "B.Fab")
		)
		(fp_line
			(start 0.67945 -0.305054)
			(end 0.12065 -0.305054)
			(stroke
				(width 0.1)
				(type default)
			)
			(layer "B.Fab")
		)
		(fp_line
			(start 0.12065 0.3048)
			(end 0.67945 0.3048)
			(stroke
				(width 0.1)
				(type default)
			)
			(layer "B.Fab")
		)
		(fp_line
			(start 0.12065 0.2794)
			(end 0.12065 0.3048)
			(stroke
				(width 0.1)
				(type default)
			)
			(layer "B.Fab")
		)
		(fp_line
			(start 0.12065 -0.2794)
			(end -0.12065 -0.2794)
			(stroke
				(width 0.1)
				(type default)
			)
			(layer "B.Fab")
		)
		(fp_line
			(start 0.12065 -0.305054)
			(end 0.12065 -0.2794)
			(stroke
				(width 0.1)
				(type default)
			)
			(layer "B.Fab")
		)
		(fp_line
			(start -0.120396 0.3048)
			(end -0.120396 0.2794)
			(stroke
				(width 0.1)
				(type default)
			)
			(layer "B.Fab")
		)
		(fp_line
			(start -0.120396 0.2794)
			(end 0.12065 0.2794)
			(stroke
				(width 0.1)
				(type default)
			)
			(layer "B.Fab")
		)
		(fp_line
			(start -0.12065 -0.2794)
			(end -0.12065 -0.3048)
			(stroke
				(width 0.1)
				(type default)
			)
			(layer "B.Fab")
		)
		(fp_line
			(start -0.12065 -0.3048)
			(end -0.67945 -0.3048)
			(stroke
				(width 0.1)
				(type default)
			)
			(layer "B.Fab")
		)
		(fp_line
			(start -0.67945 0.3048)
			(end -0.120396 0.3048)
			(stroke
				(width 0.1)
				(type default)
			)
			(layer "B.Fab")
		)
		(fp_line
			(start -0.67945 -0.3048)
			(end -0.67945 0.3048)
			(stroke
				(width 0.1)
				(type default)
			)
			(layer "B.Fab")
		)
		(pad "1" smd circle
			(at 0.40005 0)
			(size 0 0)
			(layers "B.Cu" "B.Mask" "B.Paste")
			(net "SMB_DEBUG_AUX_LVC3_USB_SCL")
		)
		(pad "2" smd circle
			(at -0.40005 0)
			(size 0 0)
			(layers "B.Cu" "B.Mask" "B.Paste")
			(net "SMB_DEBUG_AUX_LVC3_USB_R3_SCL")
		)
	)
)
